# BASEBOARD_FAB2 (Tioga Pass) — schematic netlist excerpt (pin names and nets, part order shuffled) for the footprints in the layout excerpt that follows; sources: Cadence DE-HDL packaged netlist, KiCad conversion of Wiwynn_Tioga_Pass_MB.brd

R1T29  RES  1.00K 1% CHIP  pkg 0402  page 151 : A = BMC_M_VREFCA ; B = GND
C8F5  CAP_A  0.01UF 25V 10% X7R  pkg 0402V  page 162 : A = P3V3_STBY ; B = GND
SH7L2  SHUNT  EMPTY  pkg SH0201  page 228 : A = VSENSE_PVDDQ_KLM_P ; B = PVDDQ_KLM

(kicad_pcb
	(version 20260206)
	(generator "pcbnew")
	(generator_version "10.0")
	(general
		(thickness 1.6)
		(legacy_teardrops no)
	)
	(paper "A4")
	(title_block
		(title "Wiwynn_Tioga_Pass_MB.brd")
		(comment 1 "Tioga Pass / footprints 4474-4476 of 4770")
	)
	(layers
		(0 "F.Cu" signal "TOP")
		(4 "In1.Cu" signal "L2GND")
		(6 "In2.Cu" signal "L3")
		(8 "In3.Cu" signal "L4GND")
		(10 "In4.Cu" signal "L5")
		(12 "In5.Cu" signal "L6GND")
		(14 "In6.Cu" signal "L7VCC")
		(16 "In7.Cu" signal "L8VCC")
		(18 "In8.Cu" signal "L9GND")
		(20 "In9.Cu" signal "L10")
		(22 "In10.Cu" signal "L11GND")
		(24 "In11.Cu" signal "L12")
		(26 "In12.Cu" signal "L13GND")
		(2 "B.Cu" signal "BOTTOM")
		(9 "F.Adhes" user "F.Adhesive")
		(11 "B.Adhes" user "B.Adhesive")
		(13 "F.Paste" user "Package Geometry/Pastemask Top")
		(15 "B.Paste" user "Package Geometry/Pastemask Bottom")
		(5 "F.SilkS" user "Ref Des/Silkscreen Top")
		(7 "B.SilkS" user "Ref Des/Silkscreen Bottom")
		(1 "F.Mask" user "Board Geometry/Soldermask Top")
		(3 "B.Mask" user "Board Geometry/Soldermask Bottom")
		(17 "Dwgs.User" user "User.Drawings")
		(19 "Cmts.User" user "User.Comments")
		(21 "Eco1.User" user "User.Eco1")
		(23 "Eco2.User" user "User.Eco2")
		(25 "Edge.Cuts" user "Board Geometry/Outline")
		(27 "Margin" user)
		(31 "F.CrtYd" user "Package Geometry/Place Bound Top")
		(29 "B.CrtYd" user "Package Geometry/Place Bound Bottom")
		(35 "F.Fab" user "Ref Des/Assembly Top")
		(33 "B.Fab" user "Ref Des/Assembly Bottom")
	)
	(footprint ""
		(layer "B.Cu")
		(at 85.547708 -125.99162 -90)
		(property "Reference" "SH7L2"
			(at 0 0 90)
			(layer "B.SilkS")
			(hide yes)
			(effects
				(font
					(size 1.27 1.27)
				)
				(justify mirror)
			)
		)
		(property "Value" ""
			(at 0 0 90)
			(layer "B.Fab")
			(effects
				(font
					(size 1.27 1.27)
				)
				(justify mirror)
			)
		)
		(duplicate_pad_numbers_are_jumpers no)
		(fp_poly
			(pts
				(xy 0.1651 -0.0508) (xy 0.1651 0.5842) (xy -0.1651 0.5842) (xy -0.1651 -0.0508)
			)
			(stroke
				(width 0)
				(type default)
			)
			(fill no)
			(layer "B.CrtYd")
		)
		(fp_line
			(start -0.1651 0.5842)
			(end 0.1651 0.5842)
			(stroke
				(width 0.1)
				(type default)
			)
			(layer "B.Fab")
		)
		(fp_line
			(start 0.1651 0.5842)
			(end 0.1651 -0.0508)
			(stroke
				(width 0.1)
				(type default)
			)
			(layer "B.Fab")
		)
		(fp_line
			(start -0.1651 -0.0508)
			(end -0.1651 0.5842)
			(stroke
				(width 0.1)
				(type default)
			)
			(layer "B.Fab")
		)
		(fp_line
			(start 0.1651 -0.0508)
			(end -0.1651 -0.0508)
			(stroke
				(width 0.1)
				(type default)
			)
			(layer "B.Fab")
		)
		(pad "1" smd custom
			(at 0 0 270)
			(size 0.0762 0.0762)
			(layers "B.Cu" "B.Mask" "B.Paste")
			(net "VSENSE_PVDDQ_KLM_P")
			(options
				(clearance outline)
				(anchor circle)
			)
			(primitives
				(gr_poly
					(pts
						(arc
							(start -0.1524 0.10795)
							(mid -0.098518 0.130268)
							(end -0.0762 0.18415)
						)
						(xy -0.0762 0.22225) (xy 0.0762 0.22225)
						(arc
							(start 0.0762 0.18415)
							(mid 0.098518 0.130268)
							(end 0.1524 0.10795)
						)
						(xy 0.1524 -0.22225) (xy -0.1524 -0.22225)
					)
					(width 0)
					(fill yes)
				)
			)
		)
		(pad "2" smd custom
			(at 0 0.5334 90)
			(size 0.0762 0.0762)
			(layers "B.Cu" "B.Mask" "B.Paste")
			(net "PVDDQ_KLM")
			(options
				(clearance outline)
				(anchor circle)
			)
			(primitives
				(gr_poly
					(pts
						(arc
							(start -0.1524 0.10795)
							(mid -0.098518 0.130268)
							(end -0.0762 0.18415)
						)
						(xy -0.0762 0.22225) (xy 0.0762 0.22225)
						(arc
							(start 0.0762 0.18415)
							(mid 0.098518 0.130268)
							(end 0.1524 0.10795)
						)
						(xy 0.1524 -0.22225) (xy -0.1524 -0.22225)
					)
					(width 0)
					(fill yes)
				)
			)
		)
	)
	(footprint ""
		(layer "B.Cu")
		(at 445.72555 -29.6164)
		(property "Reference" "R1T29"
			(at 0 0 0)
			(layer "B.SilkS")
			(hide yes)
			(effects
				(font
					(size 1.27 1.27)
				)
				(justify mirror)
			)
		)
		(property "Value" ""
			(at 0 0 0)
			(layer "B.Fab")
			(effects
				(font
					(size 1.27 1.27)
				)
				(justify mirror)
			)
		)
		(duplicate_pad_numbers_are_jumpers no)
		(fp_poly
			(pts
				(xy 0.2794 -0.1016) (xy -0.2794 -0.1016) (xy -0.2794 0.9906) (xy 0.2794 0.9906)
			)
			(stroke
				(width 0)
				(type default)
			)
			(fill no)
			(layer "B.CrtYd")
		)
		(fp_line
			(start -0.2794 -0.1016)
			(end 0.2794 -0.1016)
			(stroke
				(width 0.1)
				(type default)
			)
			(layer "B.Fab")
		)
		(fp_line
			(start -0.2794 0.9906)
			(end -0.2794 -0.1016)
			(stroke
				(width 0.1)
				(type default)
			)
			(layer "B.Fab")
		)
		(fp_line
			(start 0.2794 -0.1016)
			(end 0.2794 0.9906)
			(stroke
				(width 0.1)
				(type default)
			)
			(layer "B.Fab")
		)
		(fp_line
			(start 0.2794 0.9906)
			(end -0.2794 0.9906)
			(stroke
				(width 0.1)
				(type default)
			)
			(layer "B.Fab")
		)
		(pad "1" smd rect
			(at 0 0 180)
			(size 0.508 0.508)
			(layers "B.Cu" "B.Mask" "B.Paste")
			(net "BMC_M_VREFCA")
		)
		(pad "2" smd rect
			(at 0 0.889 180)
			(size 0.508 0.508)
			(layers "B.Cu" "B.Mask" "B.Paste")
			(net "GND")
		)
		(zone
			(layer "B.Cu")
			(hatch none 0.5)
			(connect_pads
				(clearance 0)
			)
			(min_thickness 0.25)
			(keepout
				(tracks allowed)
				(vias not_allowed)
				(pads allowed)
				(copperpour not_allowed)
				(footprints allowed)
			)
			(placement
				(enabled no)
				(sheetname "")
			)
			(fill
				(thermal_gap 0.5)
				(thermal_bridge_width 0.5)
				(island_removal_mode 0)
			)
			(polygon
				(pts
					(xy 445.97955 -29.3624) (xy 445.47155 -29.3624) (xy 445.47155 -28.9814) (xy 445.97955 -28.9814)
				)
			)
		)
		(zone
			(layer "B.Cu")
			(hatch none 0.5)
			(connect_pads
				(clearance 0)
			)
			(min_thickness 0.25)
			(keepout
				(tracks not_allowed)
				(vias allowed)
				(pads allowed)
				(copperpour not_allowed)
				(footprints allowed)
			)
			(placement
				(enabled no)
				(sheetname "")
			)
			(fill
				(thermal_gap 0.5)
				(thermal_bridge_width 0.5)
				(island_removal_mode 0)
			)
			(polygon
				(pts
					(xy 445.97955 -28.9814) (xy 445.47155 -28.9814) (xy 445.47155 -29.3624) (xy 445.97955 -29.3624)
				)
			)
		)
	)
	(footprint ""
		(layer "B.Cu")
		(at 366.268 -40.5892 180)
		(property "Reference" "C8F5"
			(at 0 0 0)
			(layer "B.SilkS")
			(hide yes)
			(effects
				(font
					(size 1.27 1.27)
				)
				(justify mirror)
			)
		)
		(property "Value" ""
			(at 0 0 0)
			(layer "B.Fab")
			(effects
				(font
					(size 1.27 1.27)
				)
				(justify mirror)
			)
		)
		(duplicate_pad_numbers_are_jumpers no)
		(fp_poly
			(pts
				(xy -0.3048 -0.1016) (xy -0.3048 0.9906) (xy 0.3048 0.9906) (xy 0.3048 -0.1016)
			)
			(stroke
				(width 0)
				(type default)
			)
			(fill no)
			(layer "B.CrtYd")
		)
		(fp_line
			(start 0.3048 0.9906)
			(end -0.3048 0.9906)
			(stroke
				(width 0.1)
				(type default)
			)
			(layer "B.Fab")
		)
		(fp_line
			(start 0.3048 -0.1016)
			(end 0.3048 0.9906)
			(stroke
				(width 0.1)
				(type default)
			)
			(layer "B.Fab")
		)
		(fp_line
			(start -0.3048 0.9906)
			(end -0.3048 -0.1016)
			(stroke
				(width 0.1)
				(type default)
			)
			(layer "B.Fab")
		)
		(fp_line
			(start -0.3048 -0.1016)
			(end 0.3048 -0.1016)
			(stroke
				(width 0.1)
				(type default)
			)
			(layer "B.Fab")
		)
		(pad "1" smd rect
			(at 0 0)
			(size 0.508 0.508)
			(layers "B.Cu" "B.Mask" "B.Paste")
			(net "P3V3_STBY")
		)
		(pad "2" smd rect
			(at 0 0.889)
			(size 0.508 0.508)
			(layers "B.Cu" "B.Mask" "B.Paste")
			(net "GND")
		)
		(zone
			(layer "B.Cu")
			(hatch none 0.5)
			(connect_pads
				(clearance 0)
			)
			(min_thickness 0.25)
			(keepout
				(tracks not_allowed)
				(vias allowed)
				(pads allowed)
				(copperpour not_allowed)
				(footprints allowed)
			)
			(placement
				(enabled no)
				(sheetname "")
			)
			(fill
				(thermal_gap 0.5)
				(thermal_bridge_width 0.5)
				(island_removal_mode 0)
			)
			(polygon
				(pts
					(xy 366.014 -41.2242) (xy 366.522 -41.2242) (xy 366.522 -40.8432) (xy 366.014 -40.8432)
				)
			)
		)
		(zone
			(layer "B.Cu")
			(hatch none 0.5)
			(connect_pads
				(clearance 0)
			)
			(min_thickness 0.25)
			(keepout
				(tracks allowed)
				(vias not_allowed)
				(pads allowed)
				(copperpour not_allowed)
				(footprints allowed)
			)
			(placement
				(enabled no)
				(sheetname "")
			)
			(fill
				(thermal_gap 0.5)
				(thermal_bridge_width 0.5)
				(island_removal_mode 0)
			)
			(polygon
				(pts
					(xy 366.014 -40.8432) (xy 366.522 -40.8432) (xy 366.522 -41.2242) (xy 366.014 -41.2242)
				)
			)
		)
	)
)
